# BASEBOARD_FAB2 (Tioga Pass) — schematic netlist excerpt (pin names and nets, part order shuffled) for the footprints in the layout excerpt that follows; sources: Cadence DE-HDL packaged netlist, KiCad conversion of Wiwynn_Tioga_Pass_MB.brd

J1B4  CLX-CONN3A-1-GP  pkg CONN-G3  page 199
  \1\  = A_HSC_HIGH_EN
  \2\  = A_HSC_OCP_SEL
  \3\  = A_HSC_LOW_EN

(kicad_pcb
	(version 20260206)
	(generator "pcbnew")
	(generator_version "10.0")
	(general
		(thickness 1.6)
		(legacy_teardrops no)
	)
	(paper "A4")
	(title_block
		(title "Wiwynn_Tioga_Pass_MB.brd")
		(comment 1 "Tioga Pass / footprints 1621-1621 of 4770")
	)
	(layers
		(0 "F.Cu" signal "TOP")
		(4 "In1.Cu" signal "L2GND")
		(6 "In2.Cu" signal "L3")
		(8 "In3.Cu" signal "L4GND")
		(10 "In4.Cu" signal "L5")
		(12 "In5.Cu" signal "L6GND")
		(14 "In6.Cu" signal "L7VCC")
		(16 "In7.Cu" signal "L8VCC")
		(18 "In8.Cu" signal "L9GND")
		(20 "In9.Cu" signal "L10")
		(22 "In10.Cu" signal "L11GND")
		(24 "In11.Cu" signal "L12")
		(26 "In12.Cu" signal "L13GND")
		(2 "B.Cu" signal "BOTTOM")
		(9 "F.Adhes" user "F.Adhesive")
		(11 "B.Adhes" user "B.Adhesive")
		(13 "F.Paste" user "Package Geometry/Pastemask Top")
		(15 "B.Paste" user "Package Geometry/Pastemask Bottom")
		(5 "F.SilkS" user "Ref Des/Silkscreen Top")
		(7 "B.SilkS" user "Ref Des/Silkscreen Bottom")
		(1 "F.Mask" user "Board Geometry/Soldermask Top")
		(3 "B.Mask" user "Board Geometry/Soldermask Bottom")
		(17 "Dwgs.User" user "User.Drawings")
		(19 "Cmts.User" user "User.Comments")
		(21 "Eco1.User" user "User.Eco1")
		(23 "Eco2.User" user "User.Eco2")
		(25 "Edge.Cuts" user "Board Geometry/Outline")
		(27 "Margin" user)
		(31 "F.CrtYd" user "Package Geometry/Place Bound Top")
		(29 "B.CrtYd" user "Package Geometry/Place Bound Bottom")
		(35 "F.Fab" user "Ref Des/Assembly Top")
		(33 "B.Fab" user "Ref Des/Assembly Bottom")
	)
	(footprint ""
		(layer "F.Cu")
		(at 15.072106 -110.707424 -90)
		(property "Reference" "J1B4"
			(at 0 0 270)
			(layer "F.SilkS")
			(hide yes)
			(effects
				(font
					(size 1.27 1.27)
				)
			)
		)
		(property "Value" "*"
			(at 2.6924 -3.0734 270)
			(unlocked yes)
			(layer "F.Fab")
			(hide yes)
			(effects
				(font
					(size 1.27 1.016)
					(thickness 0.1524)
				)
			)
		)
		(property "Device Type" "CLX-CONN3A-1-GP_CONN-G3-CLX-COA"
			(at 2.6924 -4.5974 270)
			(unlocked yes)
			(layer "F.Fab")
			(hide yes)
			(effects
				(font
					(size 1.27 1.016)
					(thickness 0.1524)
				)
			)
		)
		(duplicate_pad_numbers_are_jumpers no)
		(fp_line
			(start -2.6543 3.1369)
			(end -1.3335 3.1369)
			(stroke
				(width 0.3302)
				(type default)
			)
			(layer "F.SilkS")
		)
		(fp_line
			(start -2.7432 3.048)
			(end -2.7432 1.2573)
			(stroke
				(width 0.1524)
				(type default)
			)
			(layer "F.SilkS")
		)
		(fp_line
			(start -1.2446 3.048)
			(end -2.7432 3.048)
			(stroke
				(width 0.1524)
				(type default)
			)
			(layer "F.SilkS")
		)
		(fp_line
			(start 1.2446 3.048)
			(end 1.2446 1.2573)
			(stroke
				(width 0.1524)
				(type default)
			)
			(layer "F.SilkS")
		)
		(fp_line
			(start 2.7432 3.048)
			(end 1.2446 3.048)
			(stroke
				(width 0.1524)
				(type default)
			)
			(layer "F.SilkS")
		)
		(fp_line
			(start -3.2512 1.2573)
			(end -3.2512 -1.2573)
			(stroke
				(width 0.1524)
				(type default)
			)
			(layer "F.SilkS")
		)
		(fp_line
			(start -2.7432 1.2573)
			(end -3.2512 1.2573)
			(stroke
				(width 0.1524)
				(type default)
			)
			(layer "F.SilkS")
		)
		(fp_line
			(start -1.2446 1.2573)
			(end -1.2446 3.048)
			(stroke
				(width 0.1524)
				(type default)
			)
			(layer "F.SilkS")
		)
		(fp_line
			(start 1.2446 1.2573)
			(end -1.2446 1.2573)
			(stroke
				(width 0.1524)
				(type default)
			)
			(layer "F.SilkS")
		)
		(fp_line
			(start 2.7432 1.2573)
			(end 2.7432 3.048)
			(stroke
				(width 0.1524)
				(type default)
			)
			(layer "F.SilkS")
		)
		(fp_line
			(start 3.2512 1.2573)
			(end 2.7432 1.2573)
			(stroke
				(width 0.1524)
				(type default)
			)
			(layer "F.SilkS")
		)
		(fp_line
			(start -3.2512 -1.2573)
			(end -0.7493 -1.2573)
			(stroke
				(width 0.1524)
				(type default)
			)
			(layer "F.SilkS")
		)
		(fp_line
			(start -0.7493 -1.2573)
			(end -0.7493 -3.048)
			(stroke
				(width 0.1524)
				(type default)
			)
			(layer "F.SilkS")
		)
		(fp_line
			(start 0.7493 -1.2573)
			(end 3.2512 -1.2573)
			(stroke
				(width 0.1524)
				(type default)
			)
			(layer "F.SilkS")
		)
		(fp_line
			(start 3.2512 -1.2573)
			(end 3.2512 1.2573)
			(stroke
				(width 0.1524)
				(type default)
			)
			(layer "F.SilkS")
		)
		(fp_line
			(start -0.7493 -3.048)
			(end 0.7493 -3.048)
			(stroke
				(width 0.1524)
				(type default)
			)
			(layer "F.SilkS")
		)
		(fp_line
			(start 0.7493 -3.048)
			(end 0.7493 -1.2573)
			(stroke
				(width 0.1524)
				(type default)
			)
			(layer "F.SilkS")
		)
		(fp_poly
			(pts
				(xy -2.014474 3.124708) (xy -2.649474 3.759708) (xy -1.379474 3.759708)
			)
			(stroke
				(width 0)
				(type default)
			)
			(fill yes)
			(layer "F.SilkS")
		)
		(fp_poly
			(pts
				(xy -0.254 -2.2987) (xy 0.254 -2.2987) (xy 0.254 -1.0033) (xy 2.9972 -1.0033) (xy 2.9972 1.0033)
				(xy 2.2479 1.0033) (xy 2.2479 2.2987) (xy 1.7399 2.2987) (xy 1.7399 1.0033) (xy -1.7399 1.0033)
				(xy -1.7399 2.2987) (xy -2.2479 2.2987) (xy -2.2479 1.0033) (xy -2.9972 1.0033) (xy -2.9972 -1.0033)
				(xy -0.254 -1.0033)
			)
			(stroke
				(width 0)
				(type default)
			)
			(fill no)
			(layer "F.CrtYd")
		)
		(fp_poly
			(pts
				(xy -2.9972 3.302) (xy -2.9972 1.5113) (xy -3.5052 1.5113) (xy -3.5052 -1.5113) (xy -1.0033 -1.5113)
				(xy -1.0033 -3.302) (xy 1.0033 -3.302) (xy 1.0033 -1.5113) (xy 3.5052 -1.5113) (xy 3.5052 -0.00635)
				(xy 2.9972 -0.00635) (xy 2.9972 -1.0033) (xy 0.254 -1.0033) (xy 0.254 -2.2987) (xy -0.254 -2.2987)
				(xy -0.254 -1.0033) (xy -2.9972 -1.0033) (xy -2.9972 1.0033) (xy -2.2479 1.0033) (xy -2.2479 2.2987)
				(xy -1.7399 2.2987) (xy -1.7399 1.0033) (xy 1.7399 1.0033) (xy 1.7399 2.2987) (xy 2.2479 2.2987)
				(xy 2.2479 1.0033) (xy 2.9972 1.0033) (xy 2.9972 0.00635) (xy 3.5052 0.00635) (xy 3.5052 1.5113)
				(xy 2.9972 1.5113) (xy 2.9972 3.302) (xy 0.9906 3.302) (xy 0.9906 1.5113) (xy -0.9906 1.5113) (xy -0.9906 3.302)
			)
			(stroke
				(width 0)
				(type default)
			)
			(fill no)
			(layer "F.CrtYd")
		)
		(fp_poly
			(pts
				(xy -2.9972 3.302) (xy -2.9972 1.5113) (xy -3.5052 1.5113) (xy -3.5052 -1.5113) (xy -1.0033 -1.5113)
				(xy -1.0033 -3.302) (xy 1.0033 -3.302) (xy 1.0033 -1.5113) (xy 3.5052 -1.5113) (xy 3.5052 1.5113)
				(xy 2.9972 1.5113) (xy 2.9972 3.302) (xy 0.9906 3.302) (xy 0.9906 1.5113) (xy -0.9906 1.5113) (xy -0.9906 3.302)
			)
			(stroke
				(width 0)
				(type default)
			)
			(fill no)
			(layer "F.Fab")
		)
		(pad "1" smd rect
			(at -1.999996 1.397 270)
			(size 0.9906 2.794)
			(layers "F.Cu" "F.Mask" "F.Paste")
			(net "A_HSC_HIGH_EN")
		)
		(pad "2" smd rect
			(at 0 -1.397 270)
			(size 0.9906 2.794)
			(layers "F.Cu" "F.Mask" "F.Paste")
			(net "A_HSC_OCP_SEL")
		)
		(pad "3" smd rect
			(at 1.999996 1.397 270)
			(size 0.9906 2.794)
			(layers "F.Cu" "F.Mask" "F.Paste")
			(net "A_HSC_LOW_EN")
		)
	)
)
